(kicad_pcb
	(version 20260206)
	(generator "pcbnew")
	(generator_version "10.0")
	(general
		(thickness 1.6)
		(legacy_teardrops no)
	)
	(paper "A4")
	(title_block
		(title "Bryce Canyon_IOM_IOC_16318-2_OCP.brd")
		(comment 1 "Bryce Canyon / footprints 667-675 of 1605")
	)
	(layers
		(0 "F.Cu" signal "TOP")
		(4 "In1.Cu" signal "L2GND")
		(6 "In2.Cu" signal "L3")
		(8 "In3.Cu" signal "L4VCC")
		(10 "In4.Cu" signal "L5VCC")
		(12 "In5.Cu" signal "L6")
		(14 "In6.Cu" signal "L7GND")
		(2 "B.Cu" signal "BOTTOM")
		(9 "F.Adhes" user "F.Adhesive")
		(11 "B.Adhes" user "B.Adhesive")
		(13 "F.Paste" user "Package Geometry/Pastemask Top")
		(15 "B.Paste" user "Package Geometry/Pastemask Bottom")
		(5 "F.SilkS" user "Ref Des/Silkscreen Top")
		(7 "B.SilkS" user "Ref Des/Silkscreen Bottom")
		(1 "F.Mask" user "Board Geometry/Soldermask Top")
		(3 "B.Mask" user "Board Geometry/Soldermask Bottom")
		(17 "Dwgs.User" user "User.Drawings")
		(19 "Cmts.User" user "User.Comments")
		(21 "Eco1.User" user "User.Eco1")
		(23 "Eco2.User" user "User.Eco2")
		(25 "Edge.Cuts" user "Board Geometry/Outline")
		(27 "Margin" user)
		(31 "F.CrtYd" user "Package Geometry/Place Bound Top")
		(29 "B.CrtYd" user "Package Geometry/Place Bound Bottom")
		(35 "F.Fab" user "Ref Des/Assembly Top")
		(33 "B.Fab" user "Ref Des/Assembly Bottom")
	)
	(footprint ""
		(layer "F.Cu")
		(at 98.8695 -161.886392 -90)
		(property "Reference" "R32"
			(at 0 0 270)
			(layer "F.SilkS")
			(hide yes)
			(effects
				(font
					(size 1.27 1.27)
				)
			)
		)
		(property "Value" "4K7R2F-GP"
			(at 0.064008 -3.993896 270)
			(unlocked yes)
			(layer "F.Fab")
			(hide yes)
			(effects
				(font
					(size 1.016 1.016)
					(thickness 0.1524)
				)
			)
		)
		(property "Device Type" "R402H16"
			(at 0.064008 -5.517896 270)
			(unlocked yes)
			(layer "F.Fab")
			(hide yes)
			(effects
				(font
					(size 1.016 1.016)
					(thickness 0.1524)
				)
			)
		)
		(duplicate_pad_numbers_are_jumpers no)
		(fp_line
			(start -0.508 -0.9398)
			(end -0.508 0.9398)
			(stroke
				(width 0.1524)
				(type default)
			)
			(layer "F.SilkS")
		)
		(fp_line
			(start 0.508 -0.9398)
			(end -0.508 -0.9398)
			(stroke
				(width 0.1524)
				(type default)
			)
			(layer "F.SilkS")
		)
		(fp_rect
			(start -0.508 0.9398)
			(end 0.508 -0.9398)
			(stroke
				(width 0)
				(type default)
			)
			(fill no)
			(layer "F.CrtYd")
		)
		(fp_rect
			(start -0.508 0.9398)
			(end 0.508 -0.9398)
			(stroke
				(width 0)
				(type default)
			)
			(fill no)
			(layer "F.Fab")
		)
		(pad "1" smd custom
			(at 0 -0.4445 270)
			(size 0.1397 0.1397)
			(layers "F.Cu" "F.Mask" "F.Paste")
			(net "P3V3_STBY")
			(options
				(clearance outline)
				(anchor circle)
			)
			(primitives
				(gr_poly
					(pts
						(arc
							(start -0.1778 -0.2794)
							(mid -0.249642 -0.249642)
							(end -0.2794 -0.1778)
						)
						(arc
							(start -0.2794 0.1778)
							(mid -0.249642 0.249642)
							(end -0.1778 0.2794)
						)
						(arc
							(start 0.1778 0.2794)
							(mid 0.249642 0.249642)
							(end 0.2794 0.1778)
						)
						(arc
							(start 0.2794 -0.1778)
							(mid 0.249642 -0.249642)
							(end 0.1778 -0.2794)
						)
					)
					(width 0)
					(fill yes)
				)
			)
		)
		(pad "2" smd custom
			(at 0 0.4445 270)
			(size 0.1397 0.1397)
			(layers "F.Cu" "F.Mask" "F.Paste")
			(net "USB_SUSP_IND")
			(options
				(clearance outline)
				(anchor circle)
			)
			(primitives
				(gr_poly
					(pts
						(arc
							(start -0.1778 -0.2794)
							(mid -0.249642 -0.249642)
							(end -0.2794 -0.1778)
						)
						(arc
							(start -0.2794 0.1778)
							(mid -0.249642 0.249642)
							(end -0.1778 0.2794)
						)
						(arc
							(start 0.1778 0.2794)
							(mid 0.249642 0.249642)
							(end 0.2794 0.1778)
						)
						(arc
							(start 0.2794 -0.1778)
							(mid 0.249642 -0.249642)
							(end 0.1778 -0.2794)
						)
					)
					(width 0)
					(fill yes)
				)
			)
		)
	)
	(footprint ""
		(layer "F.Cu")
		(at 118.9228 -16.3322)
		(property "Reference" "R440"
			(at 0 0 0)
			(layer "F.SilkS")
			(hide yes)
			(effects
				(font
					(size 1.27 1.27)
				)
			)
		)
		(property "Value" "10R2F-L-GP"
			(at 0.064008 -3.993896 0)
			(unlocked yes)
			(layer "F.Fab")
			(hide yes)
			(effects
				(font
					(size 1.016 1.016)
					(thickness 0.1524)
				)
			)
		)
		(property "Device Type" "R402H14"
			(at 0.064008 -5.517896 0)
			(unlocked yes)
			(layer "F.Fab")
			(hide yes)
			(effects
				(font
					(size 1.016 1.016)
					(thickness 0.1524)
				)
			)
		)
		(duplicate_pad_numbers_are_jumpers no)
		(fp_line
			(start -0.508 -0.9398)
			(end -0.508 0.9398)
			(stroke
				(width 0.1524)
				(type default)
			)
			(layer "F.SilkS")
		)
		(fp_line
			(start 0.508 -0.9398)
			(end -0.508 -0.9398)
			(stroke
				(width 0.1524)
				(type default)
			)
			(layer "F.SilkS")
		)
		(fp_rect
			(start -0.508 0.9398)
			(end 0.508 -0.9398)
			(stroke
				(width 0)
				(type default)
			)
			(fill no)
			(layer "F.CrtYd")
		)
		(fp_rect
			(start -0.508 0.9398)
			(end 0.508 -0.9398)
			(stroke
				(width 0)
				(type default)
			)
			(fill no)
			(layer "F.Fab")
		)
		(pad "1" smd custom
			(at 0 -0.4445)
			(size 0.1397 0.1397)
			(layers "F.Cu" "F.Mask" "F.Paste")
			(net "MB0_CM_SENSE_R1_P")
			(options
				(clearance outline)
				(anchor circle)
			)
			(primitives
				(gr_poly
					(pts
						(arc
							(start -0.1778 -0.2794)
							(mid -0.249642 -0.249642)
							(end -0.2794 -0.1778)
						)
						(arc
							(start -0.2794 0.1778)
							(mid -0.249642 0.249642)
							(end -0.1778 0.2794)
						)
						(arc
							(start 0.1778 0.2794)
							(mid 0.249642 0.249642)
							(end 0.2794 0.1778)
						)
						(arc
							(start 0.2794 -0.1778)
							(mid 0.249642 -0.249642)
							(end 0.1778 -0.2794)
						)
					)
					(width 0)
					(fill yes)
				)
			)
		)
		(pad "2" smd custom
			(at 0 0.4445)
			(size 0.1397 0.1397)
			(layers "F.Cu" "F.Mask" "F.Paste")
			(net "MB0_CM_SENSE_P")
			(options
				(clearance outline)
				(anchor circle)
			)
			(primitives
				(gr_poly
					(pts
						(arc
							(start -0.1778 -0.2794)
							(mid -0.249642 -0.249642)
							(end -0.2794 -0.1778)
						)
						(arc
							(start -0.2794 0.1778)
							(mid -0.249642 0.249642)
							(end -0.1778 0.2794)
						)
						(arc
							(start 0.1778 0.2794)
							(mid 0.249642 0.249642)
							(end 0.2794 0.1778)
						)
						(arc
							(start 0.2794 -0.1778)
							(mid 0.249642 -0.249642)
							(end 0.1778 -0.2794)
						)
					)
					(width 0)
					(fill yes)
				)
			)
		)
	)
	(footprint ""
		(layer "F.Cu")
		(at 53.7972 -181.3306)
		(property "Reference" "C174"
			(at 0 0 0)
			(layer "F.SilkS")
			(hide yes)
			(effects
				(font
					(size 1.27 1.27)
				)
			)
		)
		(property "Value" "SC10U6D3V5KX-4GP"
			(at -0.0762 -6.1214 0)
			(unlocked yes)
			(layer "F.Fab")
			(hide yes)
			(effects
				(font
					(size 1.016 1.016)
					(thickness 0.1524)
				)
			)
		)
		(property "Device Type" "C805H58"
			(at -0.0762 -8.1534 0)
			(unlocked yes)
			(layer "F.Fab")
			(hide yes)
			(effects
				(font
					(size 1.016 1.016)
					(thickness 0.1524)
				)
			)
		)
		(duplicate_pad_numbers_are_jumpers no)
		(fp_line
			(start 0.635 0)
			(end -0.635 0)
			(stroke
				(width 0.508)
				(type default)
			)
			(layer "F.SilkS")
		)
		(fp_rect
			(start -0.9652 1.778)
			(end 0.9652 -1.778)
			(stroke
				(width 0)
				(type default)
			)
			(fill no)
			(layer "F.CrtYd")
		)
		(fp_poly
			(pts
				(xy -0.9652 -1.778) (xy 0.9652 -1.778) (xy 0.9652 1.778) (xy -0.9652 1.778)
			)
			(stroke
				(width 0)
				(type default)
			)
			(fill no)
			(layer "F.Fab")
		)
		(pad "1" smd rect
			(at 0 -0.9652)
			(size 1.397 1.143)
			(layers "F.Cu" "F.Mask" "F.Paste")
			(net "P3V3_STBY_OUT")
		)
		(pad "2" smd rect
			(at 0 0.9652)
			(size 1.397 1.143)
			(layers "F.Cu" "F.Mask" "F.Paste")
			(net "GND")
		)
	)
	(footprint ""
		(layer "F.Cu")
		(at 184.1754 -112.0902 90)
		(property "Reference" "C271"
			(at 0 0 90)
			(layer "F.SilkS")
			(hide yes)
			(effects
				(font
					(size 1.27 1.27)
				)
			)
		)
		(property "Value" "SC10U16V5KX-7-GP-U"
			(at -0.0762 -6.1214 90)
			(unlocked yes)
			(layer "F.Fab")
			(hide yes)
			(effects
				(font
					(size 1.016 1.016)
					(thickness 0.1524)
				)
			)
		)
		(property "Device Type" "C805H58"
			(at -0.0762 -8.1534 90)
			(unlocked yes)
			(layer "F.Fab")
			(hide yes)
			(effects
				(font
					(size 1.016 1.016)
					(thickness 0.1524)
				)
			)
		)
		(duplicate_pad_numbers_are_jumpers no)
		(fp_line
			(start 0.635 0)
			(end -0.635 0)
			(stroke
				(width 0.508)
				(type default)
			)
			(layer "F.SilkS")
		)
		(fp_rect
			(start -0.9652 1.778)
			(end 0.9652 -1.778)
			(stroke
				(width 0)
				(type default)
			)
			(fill no)
			(layer "F.CrtYd")
		)
		(fp_poly
			(pts
				(xy -0.9652 -1.778) (xy 0.9652 -1.778) (xy 0.9652 1.778) (xy -0.9652 1.778)
			)
			(stroke
				(width 0)
				(type default)
			)
			(fill no)
			(layer "F.Fab")
		)
		(pad "1" smd rect
			(at 0 -0.9652 90)
			(size 1.397 1.143)
			(layers "F.Cu" "F.Mask" "F.Paste")
			(net "VT235_VDDH")
		)
		(pad "2" smd rect
			(at 0 0.9652 90)
			(size 1.397 1.143)
			(layers "F.Cu" "F.Mask" "F.Paste")
			(net "GND")
		)
	)
	(footprint ""
		(layer "F.Cu")
		(at 213.2838 -119.253 -90)
		(property "Reference" "R543"
			(at 0 0 270)
			(layer "F.SilkS")
			(hide yes)
			(effects
				(font
					(size 1.27 1.27)
				)
			)
		)
		(property "Value" "0R5J-5-GP"
			(at 0 -8.9535 270)
			(unlocked yes)
			(layer "F.Fab")
			(hide yes)
			(effects
				(font
					(size 1.27 1.016)
					(thickness 0.1524)
				)
			)
		)
		(property "Device Type" "R805H24"
			(at 0 -10.6299 270)
			(unlocked yes)
			(layer "F.Fab")
			(hide yes)
			(effects
				(font
					(size 1.27 1.016)
					(thickness 0.1524)
				)
			)
		)
		(duplicate_pad_numbers_are_jumpers no)
		(fp_line
			(start -0.889 1.7018)
			(end 0.889 1.7018)
			(stroke
				(width 0.1524)
				(type default)
			)
			(layer "F.SilkS")
		)
		(fp_line
			(start 0.889 1.7018)
			(end 0.889 -0.508)
			(stroke
				(width 0.1524)
				(type default)
			)
			(layer "F.SilkS")
		)
		(fp_line
			(start -0.889 0.0762)
			(end -0.889 1.7018)
			(stroke
				(width 0.1524)
				(type default)
			)
			(layer "F.SilkS")
		)
		(fp_line
			(start -0.889 -1.7018)
			(end -0.889 0.2794)
			(stroke
				(width 0.1524)
				(type default)
			)
			(layer "F.SilkS")
		)
		(fp_line
			(start 0.889 -1.7018)
			(end 0.889 -0.381)
			(stroke
				(width 0.1524)
				(type default)
			)
			(layer "F.SilkS")
		)
		(fp_line
			(start 0.889 -1.7018)
			(end -0.889 -1.7018)
			(stroke
				(width 0.1524)
				(type default)
			)
			(layer "F.SilkS")
		)
		(fp_poly
			(pts
				(xy 0.9652 -1.778) (xy 0.9652 1.778) (xy -0.9652 1.778) (xy -0.9652 -1.778)
			)
			(stroke
				(width 0)
				(type default)
			)
			(fill no)
			(layer "F.CrtYd")
		)
		(fp_rect
			(start -0.9652 1.778)
			(end 0.9652 -1.778)
			(stroke
				(width 0)
				(type default)
			)
			(fill no)
			(layer "F.Fab")
		)
		(pad "1" smd rect
			(at 0 -0.9652 270)
			(size 1.397 1.143)
			(layers "F.Cu" "F.Mask" "F.Paste")
			(net "P1V5")
		)
		(pad "2" smd rect
			(at 0 0.9652 270)
			(size 1.397 1.143)
			(layers "F.Cu" "F.Mask" "F.Paste")
			(net "P1V5_OUT")
		)
	)
	(footprint ""
		(layer "F.Cu")
		(at 84.983828 -78.949296 90)
		(property "Reference" "VIA11"
			(at 0 0 90)
			(layer "F.SilkS")
			(hide yes)
			(effects
				(font
					(size 1.27 1.27)
				)
			)
		)
		(property "Value" "85OHM-8L-1D6MM-L16L18-GP"
			(at 4.064 0.6096 90)
			(unlocked yes)
			(layer "F.Fab")
			(hide yes)
			(effects
				(font
					(size 1.016 1.016)
					(thickness 0.1524)
				)
			)
		)
		(property "Device Type" "VIA-PCIE-4P-368076"
			(at 4.064 -0.9144 90)
			(unlocked yes)
			(layer "F.Fab")
			(hide yes)
			(effects
				(font
					(size 1.016 1.016)
					(thickness 0.1524)
				)
			)
		)
		(duplicate_pad_numbers_are_jumpers no)
		(fp_rect
			(start -1.8415 0.381)
			(end 1.8415 -0.381)
			(stroke
				(width 0)
				(type default)
			)
			(fill no)
			(layer "F.CrtYd")
		)
		(fp_rect
			(start -1.8415 0.381)
			(end 1.8415 -0.381)
			(stroke
				(width 0)
				(type default)
			)
			(fill no)
			(layer "F.Fab")
		)
		(pad "1" thru_hole circle
			(at -1.4605 0 90)
			(size 0.508 0.508)
			(drill 0.254)
			(layers "*.Cu" "*.Mask")
			(remove_unused_layers no)
			(net "GND")
			(clearance 0.127)
			(thermal_gap 0.127)
		)
		(pad "2" thru_hole circle
			(at -0.4445 0 90)
			(size 0.508 0.508)
			(drill 0.254)
			(layers "*.Cu" "*.Mask")
			(remove_unused_layers no)
			(net "PCIE_IOM_TO_COMP_18_DP")
			(clearance 0.127)
			(thermal_gap 0.127)
		)
		(pad "3" thru_hole circle
			(at 0.4445 0 90)
			(size 0.508 0.508)
			(drill 0.254)
			(layers "*.Cu" "*.Mask")
			(remove_unused_layers no)
			(net "PCIE_IOM_TO_COMP_18_DN")
			(clearance 0.127)
			(thermal_gap 0.127)
		)
		(pad "4" thru_hole circle
			(at 1.4605 0 90)
			(size 0.508 0.508)
			(drill 0.254)
			(layers "*.Cu" "*.Mask")
			(remove_unused_layers no)
			(net "GND")
			(clearance 0.127)
			(thermal_gap 0.127)
		)
	)
	(footprint ""
		(layer "F.Cu")
		(at 63.499492 -139.755626)
		(property "Reference" "TP16"
			(at 0 0 0)
			(layer "F.SilkS")
			(hide yes)
			(effects
				(font
					(size 1.27 1.27)
				)
			)
		)
		(property "Value" "TPAD28-2-GP"
			(at -0.0127 -1.6637 0)
			(unlocked yes)
			(layer "F.Fab")
			(hide yes)
			(effects
				(font
					(size 1.016 1.016)
					(thickness 0.1524)
				)
			)
		)
		(property "Device Type" "TPAD28"
			(at -0.0127 -3.1877 0)
			(unlocked yes)
			(layer "F.Fab")
			(hide yes)
			(effects
				(font
					(size 1.016 1.016)
					(thickness 0.1524)
				)
			)
		)
		(duplicate_pad_numbers_are_jumpers no)
		(fp_poly
			(pts
				(arc
					(start 0.3556 0)
					(mid -0.3556 0)
					(end 0.3556 0)
				)
			)
			(stroke
				(width 0)
				(type default)
			)
			(fill no)
			(layer "F.CrtYd")
		)
		(fp_poly
			(pts
				(arc
					(start 0.6096 0)
					(mid -0.6096 0)
					(end 0.6096 0)
				)
			)
			(stroke
				(width 0)
				(type default)
			)
			(fill no)
			(layer "F.Fab")
		)
		(pad "1" smd circle
			(at 0 0)
			(size 0.7112 0.7112)
			(layers "F.Cu" "F.Mask" "F.Paste")
			(net "I2C_M2_2_SDA")
		)
	)
	(footprint ""
		(layer "F.Cu")
		(at 98.9076 -155.0162 90)
		(property "Reference" "R23"
			(at 0 0 90)
			(layer "F.SilkS")
			(hide yes)
			(effects
				(font
					(size 1.27 1.27)
				)
			)
		)
		(property "Value" "4K7R2F-GP"
			(at 0.064008 -3.993896 90)
			(unlocked yes)
			(layer "F.Fab")
			(hide yes)
			(effects
				(font
					(size 1.016 1.016)
					(thickness 0.1524)
				)
			)
		)
		(property "Device Type" "R402H16"
			(at 0.064008 -5.517896 90)
			(unlocked yes)
			(layer "F.Fab")
			(hide yes)
			(effects
				(font
					(size 1.016 1.016)
					(thickness 0.1524)
				)
			)
		)
		(duplicate_pad_numbers_are_jumpers no)
		(fp_line
			(start 0.508 -0.9398)
			(end -0.508 -0.9398)
			(stroke
				(width 0.1524)
				(type default)
			)
			(layer "F.SilkS")
		)
		(fp_line
			(start -0.508 -0.9398)
			(end -0.508 0.9398)
			(stroke
				(width 0.1524)
				(type default)
			)
			(layer "F.SilkS")
		)
		(fp_rect
			(start -0.508 0.9398)
			(end 0.508 -0.9398)
			(stroke
				(width 0)
				(type default)
			)
			(fill no)
			(layer "F.CrtYd")
		)
		(fp_rect
			(start -0.508 0.9398)
			(end 0.508 -0.9398)
			(stroke
				(width 0)
				(type default)
			)
			(fill no)
			(layer "F.Fab")
		)
		(pad "1" smd custom
			(at 0 -0.4445 90)
			(size 0.1397 0.1397)
			(layers "F.Cu" "F.Mask" "F.Paste")
			(net "CFG_SEL0")
			(options
				(clearance outline)
				(anchor circle)
			)
			(primitives
				(gr_poly
					(pts
						(arc
							(start -0.1778 -0.2794)
							(mid -0.249642 -0.249642)
							(end -0.2794 -0.1778)
						)
						(arc
							(start -0.2794 0.1778)
							(mid -0.249642 0.249642)
							(end -0.1778 0.2794)
						)
						(arc
							(start 0.1778 0.2794)
							(mid 0.249642 0.249642)
							(end 0.2794 0.1778)
						)
						(arc
							(start 0.2794 -0.1778)
							(mid 0.249642 -0.249642)
							(end 0.1778 -0.2794)
						)
					)
					(width 0)
					(fill yes)
				)
			)
		)
		(pad "2" smd custom
			(at 0 0.4445 90)
			(size 0.1397 0.1397)
			(layers "F.Cu" "F.Mask" "F.Paste")
			(net "GND")
			(options
				(clearance outline)
				(anchor circle)
			)
			(primitives
				(gr_poly
					(pts
						(arc
							(start -0.1778 -0.2794)
							(mid -0.249642 -0.249642)
							(end -0.2794 -0.1778)
						)
						(arc
							(start -0.2794 0.1778)
							(mid -0.249642 0.249642)
							(end -0.1778 0.2794)
						)
						(arc
							(start 0.1778 0.2794)
							(mid 0.249642 0.249642)
							(end 0.2794 0.1778)
						)
						(arc
							(start 0.2794 -0.1778)
							(mid 0.249642 -0.249642)
							(end 0.1778 -0.2794)
						)
					)
					(width 0)
					(fill yes)
				)
			)
		)
	)
	(footprint ""
		(layer "F.Cu")
		(at 161.835338 -101.218238)
		(property "Reference" "R626"
			(at 0 0 0)
			(layer "F.SilkS")
			(hide yes)
			(effects
				(font
					(size 1.27 1.27)
				)
			)
		)
		(property "Value" "10KR2F-2-GP"
			(at 0.064008 -3.993896 0)
			(unlocked yes)
			(layer "F.Fab")
			(hide yes)
			(effects
				(font
					(size 1.016 1.016)
					(thickness 0.1524)
				)
			)
		)
		(property "Device Type" "R402H16"
			(at 0.064008 -5.517896 0)
			(unlocked yes)
			(layer "F.Fab")
			(hide yes)
			(effects
				(font
					(size 1.016 1.016)
					(thickness 0.1524)
				)
			)
		)
		(duplicate_pad_numbers_are_jumpers no)
		(fp_line
			(start -0.508 -0.9398)
			(end -0.508 0.9398)
			(stroke
				(width 0.1524)
				(type default)
			)
			(layer "F.SilkS")
		)
		(fp_line
			(start 0.508 -0.9398)
			(end -0.508 -0.9398)
			(stroke
				(width 0.1524)
				(type default)
			)
			(layer "F.SilkS")
		)
		(fp_rect
			(start -0.508 0.9398)
			(end 0.508 -0.9398)
			(stroke
				(width 0)
				(type default)
			)
			(fill no)
			(layer "F.CrtYd")
		)
		(fp_rect
			(start -0.508 0.9398)
			(end 0.508 -0.9398)
			(stroke
				(width 0)
				(type default)
			)
			(fill no)
			(layer "F.Fab")
		)
		(pad "1" smd custom
			(at 0 -0.4445)
			(size 0.1397 0.1397)
			(layers "F.Cu" "F.Mask" "F.Paste")
			(net "P1V8")
			(options
				(clearance outline)
				(anchor circle)
			)
			(primitives
				(gr_poly
					(pts
						(arc
							(start -0.1778 -0.2794)
							(mid -0.249642 -0.249642)
							(end -0.2794 -0.1778)
						)
						(arc
							(start -0.2794 0.1778)
							(mid -0.249642 0.249642)
							(end -0.1778 0.2794)
						)
						(arc
							(start 0.1778 0.2794)
							(mid 0.249642 0.249642)
							(end 0.2794 0.1778)
						)
						(arc
							(start 0.2794 -0.1778)
							(mid 0.249642 -0.249642)
							(end 0.1778 -0.2794)
						)
					)
					(width 0)
					(fill yes)
				)
			)
		)
		(pad "2" smd custom
			(at 0 0.4445)
			(size 0.1397 0.1397)
			(layers "F.Cu" "F.Mask" "F.Paste")
			(net "SYS_HB_LED")
			(options
				(clearance outline)
				(anchor circle)
			)
			(primitives
				(gr_poly
					(pts
						(arc
							(start -0.1778 -0.2794)
							(mid -0.249642 -0.249642)
							(end -0.2794 -0.1778)
						)
						(arc
							(start -0.2794 0.1778)
							(mid -0.249642 0.249642)
							(end -0.1778 0.2794)
						)
						(arc
							(start 0.1778 0.2794)
							(mid 0.249642 0.249642)
							(end 0.2794 0.1778)
						)
						(arc
							(start 0.2794 -0.1778)
							(mid 0.249642 -0.249642)
							(end 0.1778 -0.2794)
						)
					)
					(width 0)
					(fill yes)
				)
			)
		)
	)
)
